(kicad_pcb
	(version 20260206)
	(generator "pcbnew")
	(generator_version "10.0")
	(general
		(thickness 1.6)
		(legacy_teardrops no)
	)
	(paper "A4")
	(title_block
		(title "04192023_DAF0TMB3IC0_F0TG_MB_C_brd_V02_OCP.brd")
		(comment 1 "Grand Teton / footprints 1251-1256 of 8354")
	)
	(layers
		(0 "F.Cu" signal "TOP")
		(4 "In1.Cu" signal "GND")
		(6 "In2.Cu" signal "IN1")
		(8 "In3.Cu" signal "GND1")
		(10 "In4.Cu" signal "IN2")
		(12 "In5.Cu" signal "GND2")
		(14 "In6.Cu" signal "IN3")
		(16 "In7.Cu" signal "GND3")
		(18 "In8.Cu" signal "VCC")
		(20 "In9.Cu" signal "VCC1")
		(22 "In10.Cu" signal "GND4")
		(24 "In11.Cu" signal "IN4")
		(26 "In12.Cu" signal "GND5")
		(28 "In13.Cu" signal "IN5")
		(30 "In14.Cu" signal "GND6")
		(32 "In15.Cu" signal "IN6")
		(34 "In16.Cu" signal "GND7")
		(2 "B.Cu" signal "BOTTOM")
		(9 "F.Adhes" user "F.Adhesive")
		(11 "B.Adhes" user "B.Adhesive")
		(13 "F.Paste" user "Package Geometry/Pastemask Top")
		(15 "B.Paste" user "Package Geometry/Pastemask Bottom")
		(5 "F.SilkS" user "Ref Des/Silkscreen Top")
		(7 "B.SilkS" user "Ref Des/Silkscreen Bottom")
		(1 "F.Mask" user "Board Geometry/Soldermask Top")
		(3 "B.Mask" user "Board Geometry/Soldermask Bottom")
		(17 "Dwgs.User" user "User.Drawings")
		(19 "Cmts.User" user "User.Comments")
		(21 "Eco1.User" user "User.Eco1")
		(23 "Eco2.User" user "User.Eco2")
		(25 "Edge.Cuts" user "Board Geometry/Outline")
		(27 "Margin" user)
		(31 "F.CrtYd" user "Package Geometry/Place Bound Top")
		(29 "B.CrtYd" user "Package Geometry/Place Bound Bottom")
		(35 "F.Fab" user "Ref Des/Assembly Top")
		(33 "B.Fab" user "Ref Des/Assembly Bottom")
	)
	(footprint ""
		(layer "F.Cu")
		(at 50.254662 -401.98294 90)
		(property "Reference" "C7041"
			(at 0 0 90)
			(layer "F.SilkS")
			(hide yes)
			(effects
				(font
					(size 1.27 1.27)
				)
			)
		)
		(property "Value" ""
			(at 0 0 90)
			(layer "F.Fab")
			(effects
				(font
					(size 1.27 1.27)
				)
			)
		)
		(duplicate_pad_numbers_are_jumpers no)
		(fp_line
			(start 1.524 -0.762)
			(end 1.524 0.762)
			(stroke
				(width 0.1524)
				(type default)
			)
			(layer "F.SilkS")
		)
		(fp_line
			(start -1.524 -0.762)
			(end 1.524 -0.762)
			(stroke
				(width 0.1524)
				(type default)
			)
			(layer "F.SilkS")
		)
		(fp_line
			(start 1.524 0.762)
			(end -1.524 0.762)
			(stroke
				(width 0.1524)
				(type default)
			)
			(layer "F.SilkS")
		)
		(fp_line
			(start -1.524 0.762)
			(end -1.524 -0.762)
			(stroke
				(width 0.1524)
				(type default)
			)
			(layer "F.SilkS")
		)
		(fp_line
			(start 1.1049 -0.724916)
			(end -1.1049 -0.724916)
			(stroke
				(width 0.1)
				(type default)
			)
			(layer "F.Fab")
		)
		(fp_line
			(start -1.1049 -0.724916)
			(end -1.1049 0.724916)
			(stroke
				(width 0.1)
				(type default)
			)
			(layer "F.Fab")
		)
		(fp_line
			(start 1.1049 0.724916)
			(end 1.1049 -0.724916)
			(stroke
				(width 0.1)
				(type default)
			)
			(layer "F.Fab")
		)
		(fp_line
			(start -1.1049 0.724916)
			(end 1.1049 0.724916)
			(stroke
				(width 0.1)
				(type default)
			)
			(layer "F.Fab")
		)
		(pad "1" smd rect
			(at -0.889 0 270)
			(size 1.016 1.27)
			(layers "F.Cu" "F.Mask" "F.Paste")
			(net "P0V9_CPU1_RT_2D")
		)
		(pad "2" smd rect
			(at 0.889 0 270)
			(size 1.016 1.27)
			(layers "F.Cu" "F.Mask" "F.Paste")
			(net "GND")
		)
	)
	(footprint ""
		(layer "F.Cu")
		(at 321.183 -194.31 180)
		(property "Reference" "R425"
			(at 0 0 180)
			(layer "F.SilkS")
			(hide yes)
			(effects
				(font
					(size 1.27 1.27)
				)
			)
		)
		(property "Value" ""
			(at 0 0 180)
			(layer "F.Fab")
			(effects
				(font
					(size 1.27 1.27)
				)
			)
		)
		(duplicate_pad_numbers_are_jumpers no)
		(fp_line
			(start 0.7874 0.4064)
			(end -0.7874 0.4064)
			(stroke
				(width 0.1524)
				(type default)
			)
			(layer "F.SilkS")
		)
		(fp_line
			(start 0.7874 -0.4064)
			(end 0.7874 0.4064)
			(stroke
				(width 0.1524)
				(type default)
			)
			(layer "F.SilkS")
		)
		(fp_line
			(start -0.7874 0.4064)
			(end -0.7874 -0.4064)
			(stroke
				(width 0.1524)
				(type default)
			)
			(layer "F.SilkS")
		)
		(fp_line
			(start -0.7874 -0.4064)
			(end 0.7874 -0.4064)
			(stroke
				(width 0.1524)
				(type default)
			)
			(layer "F.SilkS")
		)
		(fp_line
			(start 0.67945 0.3048)
			(end 0.120396 0.3048)
			(stroke
				(width 0.1)
				(type default)
			)
			(layer "F.Fab")
		)
		(fp_line
			(start 0.67945 -0.3048)
			(end 0.67945 0.3048)
			(stroke
				(width 0.1)
				(type default)
			)
			(layer "F.Fab")
		)
		(fp_line
			(start 0.12065 -0.2794)
			(end 0.12065 -0.3048)
			(stroke
				(width 0.1)
				(type default)
			)
			(layer "F.Fab")
		)
		(fp_line
			(start 0.12065 -0.3048)
			(end 0.67945 -0.3048)
			(stroke
				(width 0.1)
				(type default)
			)
			(layer "F.Fab")
		)
		(fp_line
			(start 0.120396 0.3048)
			(end 0.120396 0.2794)
			(stroke
				(width 0.1)
				(type default)
			)
			(layer "F.Fab")
		)
		(fp_line
			(start 0.120396 0.2794)
			(end -0.12065 0.2794)
			(stroke
				(width 0.1)
				(type default)
			)
			(layer "F.Fab")
		)
		(fp_line
			(start -0.12065 0.3048)
			(end -0.67945 0.3048)
			(stroke
				(width 0.1)
				(type default)
			)
			(layer "F.Fab")
		)
		(fp_line
			(start -0.12065 0.2794)
			(end -0.12065 0.3048)
			(stroke
				(width 0.1)
				(type default)
			)
			(layer "F.Fab")
		)
		(fp_line
			(start -0.12065 -0.2794)
			(end 0.12065 -0.2794)
			(stroke
				(width 0.1)
				(type default)
			)
			(layer "F.Fab")
		)
		(fp_line
			(start -0.12065 -0.305054)
			(end -0.12065 -0.2794)
			(stroke
				(width 0.1)
				(type default)
			)
			(layer "F.Fab")
		)
		(fp_line
			(start -0.67945 0.3048)
			(end -0.67945 -0.305054)
			(stroke
				(width 0.1)
				(type default)
			)
			(layer "F.Fab")
		)
		(fp_line
			(start -0.67945 -0.305054)
			(end -0.12065 -0.305054)
			(stroke
				(width 0.1)
				(type default)
			)
			(layer "F.Fab")
		)
		(pad "1" smd circle
			(at -0.40005 0 180)
			(size 0 0)
			(layers "F.Cu" "F.Mask" "F.Paste")
			(net "PVDD11_S3_P0")
		)
		(pad "2" smd circle
			(at 0.40005 0 180)
			(size 0 0)
			(layers "F.Cu" "F.Mask" "F.Paste")
			(net "I3C_0_SPD_DDRAF_CPU0_R_SCL")
		)
	)
	(footprint ""
		(layer "F.Cu")
		(at 297.32605 -150.538942 180)
		(property "Reference" "R1331"
			(at 0 0 180)
			(layer "F.SilkS")
			(hide yes)
			(effects
				(font
					(size 1.27 1.27)
				)
			)
		)
		(property "Value" ""
			(at 0 0 180)
			(layer "F.Fab")
			(effects
				(font
					(size 1.27 1.27)
				)
			)
		)
		(duplicate_pad_numbers_are_jumpers no)
		(fp_line
			(start 0.7874 0.4064)
			(end -0.7874 0.4064)
			(stroke
				(width 0.1524)
				(type default)
			)
			(layer "F.SilkS")
		)
		(fp_line
			(start 0.7874 -0.4064)
			(end 0.7874 0.4064)
			(stroke
				(width 0.1524)
				(type default)
			)
			(layer "F.SilkS")
		)
		(fp_line
			(start -0.7874 0.4064)
			(end -0.7874 -0.4064)
			(stroke
				(width 0.1524)
				(type default)
			)
			(layer "F.SilkS")
		)
		(fp_line
			(start -0.7874 -0.4064)
			(end 0.7874 -0.4064)
			(stroke
				(width 0.1524)
				(type default)
			)
			(layer "F.SilkS")
		)
		(fp_line
			(start 0.67945 0.3048)
			(end 0.120396 0.3048)
			(stroke
				(width 0.1)
				(type default)
			)
			(layer "F.Fab")
		)
		(fp_line
			(start 0.67945 -0.3048)
			(end 0.67945 0.3048)
			(stroke
				(width 0.1)
				(type default)
			)
			(layer "F.Fab")
		)
		(fp_line
			(start 0.12065 -0.2794)
			(end 0.12065 -0.3048)
			(stroke
				(width 0.1)
				(type default)
			)
			(layer "F.Fab")
		)
		(fp_line
			(start 0.12065 -0.3048)
			(end 0.67945 -0.3048)
			(stroke
				(width 0.1)
				(type default)
			)
			(layer "F.Fab")
		)
		(fp_line
			(start 0.120396 0.3048)
			(end 0.120396 0.2794)
			(stroke
				(width 0.1)
				(type default)
			)
			(layer "F.Fab")
		)
		(fp_line
			(start 0.120396 0.2794)
			(end -0.12065 0.2794)
			(stroke
				(width 0.1)
				(type default)
			)
			(layer "F.Fab")
		)
		(fp_line
			(start -0.12065 0.3048)
			(end -0.67945 0.3048)
			(stroke
				(width 0.1)
				(type default)
			)
			(layer "F.Fab")
		)
		(fp_line
			(start -0.12065 0.2794)
			(end -0.12065 0.3048)
			(stroke
				(width 0.1)
				(type default)
			)
			(layer "F.Fab")
		)
		(fp_line
			(start -0.12065 -0.2794)
			(end 0.12065 -0.2794)
			(stroke
				(width 0.1)
				(type default)
			)
			(layer "F.Fab")
		)
		(fp_line
			(start -0.12065 -0.305054)
			(end -0.12065 -0.2794)
			(stroke
				(width 0.1)
				(type default)
			)
			(layer "F.Fab")
		)
		(fp_line
			(start -0.67945 0.3048)
			(end -0.67945 -0.305054)
			(stroke
				(width 0.1)
				(type default)
			)
			(layer "F.Fab")
		)
		(fp_line
			(start -0.67945 -0.305054)
			(end -0.12065 -0.305054)
			(stroke
				(width 0.1)
				(type default)
			)
			(layer "F.Fab")
		)
		(pad "1" smd rect
			(at -0.40005 0)
			(size 0.4572 0.508)
			(layers "F.Cu" "F.Mask" "F.Paste")
			(net "I3C_SPD_DDRAF_CPU0_BYPASS_SDA")
		)
		(pad "2" smd rect
			(at 0.40005 0)
			(size 0.4572 0.508)
			(layers "F.Cu" "F.Mask" "F.Paste")
			(net "I3C_SPD_DDRAF_CPU0_SDA")
		)
	)
	(footprint ""
		(layer "F.Cu")
		(at 12.786106 -105.50398 90)
		(property "Reference" "R2787"
			(at 0 0 90)
			(layer "F.SilkS")
			(hide yes)
			(effects
				(font
					(size 1.27 1.27)
				)
			)
		)
		(property "Value" ""
			(at 0 0 90)
			(layer "F.Fab")
			(effects
				(font
					(size 1.27 1.27)
				)
			)
		)
		(duplicate_pad_numbers_are_jumpers no)
		(fp_line
			(start 0.7874 -0.4064)
			(end 0.7874 0.4064)
			(stroke
				(width 0.1524)
				(type default)
			)
			(layer "F.SilkS")
		)
		(fp_line
			(start -0.7874 -0.4064)
			(end 0.7874 -0.4064)
			(stroke
				(width 0.1524)
				(type default)
			)
			(layer "F.SilkS")
		)
		(fp_line
			(start 0.7874 0.4064)
			(end -0.7874 0.4064)
			(stroke
				(width 0.1524)
				(type default)
			)
			(layer "F.SilkS")
		)
		(fp_line
			(start -0.7874 0.4064)
			(end -0.7874 -0.4064)
			(stroke
				(width 0.1524)
				(type default)
			)
			(layer "F.SilkS")
		)
		(fp_line
			(start -0.12065 -0.305054)
			(end -0.12065 -0.2794)
			(stroke
				(width 0.1)
				(type default)
			)
			(layer "F.Fab")
		)
		(fp_line
			(start -0.67945 -0.305054)
			(end -0.12065 -0.305054)
			(stroke
				(width 0.1)
				(type default)
			)
			(layer "F.Fab")
		)
		(fp_line
			(start 0.67945 -0.3048)
			(end 0.67945 0.3048)
			(stroke
				(width 0.1)
				(type default)
			)
			(layer "F.Fab")
		)
		(fp_line
			(start 0.12065 -0.3048)
			(end 0.67945 -0.3048)
			(stroke
				(width 0.1)
				(type default)
			)
			(layer "F.Fab")
		)
		(fp_line
			(start 0.12065 -0.2794)
			(end 0.12065 -0.3048)
			(stroke
				(width 0.1)
				(type default)
			)
			(layer "F.Fab")
		)
		(fp_line
			(start -0.12065 -0.2794)
			(end 0.12065 -0.2794)
			(stroke
				(width 0.1)
				(type default)
			)
			(layer "F.Fab")
		)
		(fp_line
			(start 0.120396 0.2794)
			(end -0.12065 0.2794)
			(stroke
				(width 0.1)
				(type default)
			)
			(layer "F.Fab")
		)
		(fp_line
			(start -0.12065 0.2794)
			(end -0.12065 0.3048)
			(stroke
				(width 0.1)
				(type default)
			)
			(layer "F.Fab")
		)
		(fp_line
			(start 0.67945 0.3048)
			(end 0.120396 0.3048)
			(stroke
				(width 0.1)
				(type default)
			)
			(layer "F.Fab")
		)
		(fp_line
			(start 0.120396 0.3048)
			(end 0.120396 0.2794)
			(stroke
				(width 0.1)
				(type default)
			)
			(layer "F.Fab")
		)
		(fp_line
			(start -0.12065 0.3048)
			(end -0.67945 0.3048)
			(stroke
				(width 0.1)
				(type default)
			)
			(layer "F.Fab")
		)
		(fp_line
			(start -0.67945 0.3048)
			(end -0.67945 -0.305054)
			(stroke
				(width 0.1)
				(type default)
			)
			(layer "F.Fab")
		)
		(pad "1" smd rect
			(at -0.40005 0 270)
			(size 0.4572 0.508)
			(layers "F.Cu" "F.Mask" "F.Paste")
			(net "USB2_HUB_SWB_DN")
		)
		(pad "2" smd rect
			(at 0.40005 0 270)
			(size 0.4572 0.508)
			(layers "F.Cu" "F.Mask" "F.Paste")
			(net "USB2_HUB_BUF_SWB_R_DN")
		)
	)
	(footprint ""
		(layer "F.Cu")
		(at 343.096088 -171.746672 -90)
		(property "Reference" "PC497"
			(at 0 0 270)
			(layer "F.SilkS")
			(hide yes)
			(effects
				(font
					(size 1.27 1.27)
				)
			)
		)
		(property "Value" ""
			(at 0 0 270)
			(layer "F.Fab")
			(effects
				(font
					(size 1.27 1.27)
				)
			)
		)
		(duplicate_pad_numbers_are_jumpers no)
		(fp_line
			(start -0.7874 0.4064)
			(end -0.7874 -0.4064)
			(stroke
				(width 0.1524)
				(type default)
			)
			(layer "F.SilkS")
		)
		(fp_line
			(start 0.7874 0.4064)
			(end -0.7874 0.4064)
			(stroke
				(width 0.1524)
				(type default)
			)
			(layer "F.SilkS")
		)
		(fp_line
			(start -0.7874 -0.4064)
			(end 0.7874 -0.4064)
			(stroke
				(width 0.1524)
				(type default)
			)
			(layer "F.SilkS")
		)
		(fp_line
			(start 0.7874 -0.4064)
			(end 0.7874 0.4064)
			(stroke
				(width 0.1524)
				(type default)
			)
			(layer "F.SilkS")
		)
		(fp_line
			(start -0.67945 0.3048)
			(end -0.67945 -0.305054)
			(stroke
				(width 0.1)
				(type default)
			)
			(layer "F.Fab")
		)
		(fp_line
			(start -0.12065 0.3048)
			(end -0.67945 0.3048)
			(stroke
				(width 0.1)
				(type default)
			)
			(layer "F.Fab")
		)
		(fp_line
			(start 0.120396 0.3048)
			(end 0.120396 0.2794)
			(stroke
				(width 0.1)
				(type default)
			)
			(layer "F.Fab")
		)
		(fp_line
			(start 0.67945 0.3048)
			(end 0.120396 0.3048)
			(stroke
				(width 0.1)
				(type default)
			)
			(layer "F.Fab")
		)
		(fp_line
			(start -0.12065 0.2794)
			(end -0.12065 0.3048)
			(stroke
				(width 0.1)
				(type default)
			)
			(layer "F.Fab")
		)
		(fp_line
			(start 0.120396 0.2794)
			(end -0.12065 0.2794)
			(stroke
				(width 0.1)
				(type default)
			)
			(layer "F.Fab")
		)
		(fp_line
			(start -0.12065 -0.2794)
			(end 0.12065 -0.2794)
			(stroke
				(width 0.1)
				(type default)
			)
			(layer "F.Fab")
		)
		(fp_line
			(start 0.12065 -0.2794)
			(end 0.12065 -0.3048)
			(stroke
				(width 0.1)
				(type default)
			)
			(layer "F.Fab")
		)
		(fp_line
			(start 0.12065 -0.3048)
			(end 0.67945 -0.3048)
			(stroke
				(width 0.1)
				(type default)
			)
			(layer "F.Fab")
		)
		(fp_line
			(start 0.67945 -0.3048)
			(end 0.67945 0.3048)
			(stroke
				(width 0.1)
				(type default)
			)
			(layer "F.Fab")
		)
		(fp_line
			(start -0.67945 -0.305054)
			(end -0.12065 -0.305054)
			(stroke
				(width 0.1)
				(type default)
			)
			(layer "F.Fab")
		)
		(fp_line
			(start -0.12065 -0.305054)
			(end -0.12065 -0.2794)
			(stroke
				(width 0.1)
				(type default)
			)
			(layer "F.Fab")
		)
		(pad "1" smd circle
			(at -0.40005 0 270)
			(size 0 0)
			(layers "F.Cu" "F.Mask" "F.Paste")
			(net "PVDDCR_CPU0_P0")
		)
		(pad "2" smd circle
			(at 0.40005 0 270)
			(size 0 0)
			(layers "F.Cu" "F.Mask" "F.Paste")
			(net "GND")
		)
	)
	(footprint ""
		(layer "F.Cu")
		(at 201.137266 -121.795794)
		(property "Reference" "R6777"
			(at 0 0 0)
			(layer "F.SilkS")
			(hide yes)
			(effects
				(font
					(size 1.27 1.27)
				)
			)
		)
		(property "Value" ""
			(at 0 0 0)
			(layer "F.Fab")
			(effects
				(font
					(size 1.27 1.27)
				)
			)
		)
		(duplicate_pad_numbers_are_jumpers no)
		(fp_line
			(start -0.7874 -0.4064)
			(end 0.7874 -0.4064)
			(stroke
				(width 0.1524)
				(type default)
			)
			(layer "F.SilkS")
		)
		(fp_line
			(start -0.7874 0.4064)
			(end -0.7874 -0.4064)
			(stroke
				(width 0.1524)
				(type default)
			)
			(layer "F.SilkS")
		)
		(fp_line
			(start 0.7874 -0.4064)
			(end 0.7874 0.4064)
			(stroke
				(width 0.1524)
				(type default)
			)
			(layer "F.SilkS")
		)
		(fp_line
			(start 0.7874 0.4064)
			(end -0.7874 0.4064)
			(stroke
				(width 0.1524)
				(type default)
			)
			(layer "F.SilkS")
		)
		(fp_line
			(start -0.67945 -0.305054)
			(end -0.12065 -0.305054)
			(stroke
				(width 0.1)
				(type default)
			)
			(layer "F.Fab")
		)
		(fp_line
			(start -0.67945 0.3048)
			(end -0.67945 -0.305054)
			(stroke
				(width 0.1)
				(type default)
			)
			(layer "F.Fab")
		)
		(fp_line
			(start -0.12065 -0.305054)
			(end -0.12065 -0.2794)
			(stroke
				(width 0.1)
				(type default)
			)
			(layer "F.Fab")
		)
		(fp_line
			(start -0.12065 -0.2794)
			(end 0.12065 -0.2794)
			(stroke
				(width 0.1)
				(type default)
			)
			(layer "F.Fab")
		)
		(fp_line
			(start -0.12065 0.2794)
			(end -0.12065 0.3048)
			(stroke
				(width 0.1)
				(type default)
			)
			(layer "F.Fab")
		)
		(fp_line
			(start -0.12065 0.3048)
			(end -0.67945 0.3048)
			(stroke
				(width 0.1)
				(type default)
			)
			(layer "F.Fab")
		)
		(fp_line
			(start 0.120396 0.2794)
			(end -0.12065 0.2794)
			(stroke
				(width 0.1)
				(type default)
			)
			(layer "F.Fab")
		)
		(fp_line
			(start 0.120396 0.3048)
			(end 0.120396 0.2794)
			(stroke
				(width 0.1)
				(type default)
			)
			(layer "F.Fab")
		)
		(fp_line
			(start 0.12065 -0.3048)
			(end 0.67945 -0.3048)
			(stroke
				(width 0.1)
				(type default)
			)
			(layer "F.Fab")
		)
		(fp_line
			(start 0.12065 -0.2794)
			(end 0.12065 -0.3048)
			(stroke
				(width 0.1)
				(type default)
			)
			(layer "F.Fab")
		)
		(fp_line
			(start 0.67945 -0.3048)
			(end 0.67945 0.3048)
			(stroke
				(width 0.1)
				(type default)
			)
			(layer "F.Fab")
		)
		(fp_line
			(start 0.67945 0.3048)
			(end 0.120396 0.3048)
			(stroke
				(width 0.1)
				(type default)
			)
			(layer "F.Fab")
		)
		(pad "1" smd circle
			(at -0.40005 0)
			(size 0 0)
			(layers "F.Cu" "F.Mask" "F.Paste")
			(net "RST_SMB_RT_R2_N")
		)
		(pad "2" smd circle
			(at 0.40005 0)
			(size 0 0)
			(layers "F.Cu" "F.Mask" "F.Paste")
			(net "RST_SMB_RT_R1_N")
		)
	)
)
